FILE_TYPE = CONNECTIVITY;
{Allegro Design Entry HDL 17.2-2016 S066 (3851973) 4/6/2020}
"PAGE_NUMBER" = 516;
0"NC";
1"XP1R8V_FPGA_PG";
2"SG\g";
3"SG\g";
4"XP3R3V\g";
5"SG\g";
6"FPGA_CFG_INIT_N";
7"UN$516$CAPACITOR$I13$1";
8"XP12R0V\g";
9"XP5R0V_BT";
10"UN$516$CAPACITOR$I27$1";
11"UN$516$CAPACITOR$I37$2";
12"XP5R0V_SS";
13"XP5R0V_RT";
14"XP5R0V_PG";
15"SG\g";
16"R_XP5R0V_EN";
17"XP5R0V_AGND";
18"SG\g";
19"XP5R0V_COMP";
20"VIN_XP5R0V";
21"SG\g";
22"XP5R0V_SW";
23"XP5R0V_AGND";
24"XP5R0V_FB_R_TO_AGND";
25"UN$516$CAPACITOR$I29$1";
26"XP5R0V\g";
27"SG\g";
%"RESISTOR"
"2","(-13950,6100)","0","passive","I1";
;
$LOCATION"R47"
CDS_LOCATION"R47"
$SEC"1"
CDS_SEC"1"
VALUE"10KOHM"
PACKAGE"0402"
NO_ASSY"TRUE"
TOLERANCE"1%"
CLS_PN"G155-11002-01"
CDS_LMAN_SYM_OUTLINE"-50,50,50,-100"
CDS_LIB"passive";
"1"
$PN"1"4;
"2"
$PN"2"14;
%"CAPACITOR"
"2","(-12600,6600)","0","passive","I10";
;
$LOCATION"C29"
CDS_LOCATION"C29"
$SEC"1"
CDS_SEC"1"
PACKAGE"0402"
VALUE"0.1UF"
VOLTAGE"10V"
CDS_LMAN_SYM_OUTLINE"-50,0,50,-50"
CDS_LIB"passive"
CLS_PN"G105-0B104-CK"
TOLERANCE"10%";
"2"
$PN"2"15;
"1"
$PN"1"16;
%"CAPACITOR"
"2","(-11850,6100)","0","passive","I11";
;
$LOCATION"C31"
CDS_LOCATION"C31"
$SEC"1"
CDS_SEC"1"
VALUE"0.022UF"
PACKAGE"0402"
VOLTAGE"25V"
CLS_PN"G105-0B223-EK"
CDS_LMAN_SYM_OUTLINE"-50,0,50,-50"
CDS_LIB"passive"
TOLERANCE"10%";
"2"
$PN"2"17;
"1"
$PN"1"12;
%"RESISTOR"
"2","(-11300,5900)","0","passive","I12";
;
$LOCATION"R29"
CDS_LOCATION"R29"
$SEC"1"
CDS_SEC"1"
VALUE"100KOHM"
PACKAGE"0402"
TOLERANCE"1%"
CDS_LIB"passive"
CDS_LMAN_SYM_OUTLINE"-50,50,50,-100"
CLS_PN"G155-11003-01";
"1"
$PN"1"13;
"2"
$PN"2"17;
%"CAPACITOR"
"2","(-10700,5750)","0","passive","I13";
;
$LOCATION"C42"
CDS_LOCATION"C42"
$SEC"1"
CDS_SEC"1"
VALUE"2200PF"
VOLTAGE"50V"
PACKAGE"0402"
CLS_PN"G105-0B222-FK"
CDS_LIB"passive"
CDS_LMAN_SYM_OUTLINE"-50,0,50,-50"
TOLERANCE"10%";
"2"
$PN"2"17;
"1"
$PN"1"7;
%"RESISTOR"
"2","(-10700,6050)","0","passive","I14";
;
$LOCATION"R30"
CDS_LOCATION"R30"
$SEC"1"
CDS_SEC"1"
VALUE"2.2KOHM"
PACKAGE"0402"
CLS_PN"G155-12201-01"
CDS_LMAN_SYM_OUTLINE"-50,50,50,-100"
CDS_LIB"passive"
TOLERANCE"1%";
"1"
$PN"1"19;
"2"
$PN"2"7;
%"CAPACITOR"
"2","(-10050,5850)","0","passive","I15";
;
$LOCATION"C43"
CDS_LOCATION"C43"
$SEC"1"
CDS_SEC"1"
VALUE"18PF"
PACKAGE"0201"
VOLTAGE"50V"
TOLERANCE"5%"
CLS_PN"G104-0A180-FJ"
CDS_LMAN_SYM_OUTLINE"-50,0,50,-50"
CDS_LIB"passive";
"2"
$PN"2"17;
"1"
$PN"1"19;
%"RESISTOR"
"2","(-12700,7900)","0","passive","I16";
;
$LOCATION"R49"
CDS_LOCATION"R49"
$SEC"1"
CDS_SEC"1"
VALUE"10KOHM"
PACKAGE"0402"
NO_ASSY"TRUE"
TOLERANCE"1%"
CLS_PN"G155-11002-01"
CDS_LIB"passive"
CDS_LMAN_SYM_OUTLINE"-50,50,50,-100";
"1"
$PN"1"20;
"2"
$PN"2"16;
%"FERRITEBEAD"
"1","(-13200,8300)","0","passive","I17";
;
$LOCATION"L7"
CDS_LOCATION"L7"
$SEC"1"
CDS_SEC"1"
PACKAGE"0603"
VALUE"26OHM"
TOLERANCE"25%"
CLS_PN"G191-10101-01"
CDS_LMAN_SYM_OUTLINE"0,0,200,-100"
CDS_LIB"passive";
"2"
$PN"2"20;
"1"
$PN"1"8;
%"CAPACITOR"
"2","(-12250,7950)","0","passive","I18";
;
$LOCATION"C30"
CDS_LOCATION"C30"
$SEC"1"
CDS_SEC"1"
PACKAGE"0805"
VOLTAGE"25V"
VALUE"10UF"
CLS_PN"G107-0F106-EM"
CDS_LMAN_SYM_OUTLINE"-50,0,50,-50"
CDS_LIB"passive"
TOLERANCE"20%";
"2"
$PN"2"18;
"1"
$PN"1"20;
%"CAPACITOR"
"2","(-11800,7950)","0","passive","I19";
;
$LOCATION"C32"
CDS_LOCATION"C32"
$SEC"1"
CDS_SEC"1"
PACKAGE"0805"
VOLTAGE"25V"
VALUE"10UF"
CDS_LIB"passive"
CDS_LMAN_SYM_OUTLINE"-50,0,50,-50"
CLS_PN"G107-0F106-EM"
TOLERANCE"20%";
"2"
$PN"2"18;
"1"
$PN"1"20;
%"VCC"
"1","(-14000,6500)","0","cls","I2";
;
HDL_POWER"XP3R3V"
VOLTAGE"3.3"
BODY_TYPE"PLUMBING"
CDS_LMAN_SYM_OUTLINE"-250,250,250,-250"
CDS_LIB"cls";
"$PIN0"4;
%"CAPACITOR"
"2","(-11350,7950)","0","passive","I20";
;
$LOCATION"C33"
CDS_LOCATION"C33"
$SEC"1"
CDS_SEC"1"
PACKAGE"0402"
VOLTAGE"25V"
VALUE"0.1UF"
CLS_PN"G105-0B104-EK"
CDS_LMAN_SYM_OUTLINE"-50,0,50,-50"
CDS_LIB"passive"
TOLERANCE"10%";
"2"
$PN"2"18;
"1"
$PN"1"20;
%"GND_SG"
"1","(-10850,7400)","0","cls","I21";
;
HDL_POWER"SG"
BODY_TYPE"PLUMBING"
CDS_LIB"cls"
CDS_LMAN_SYM_OUTLINE"0,0,100,-50";
"SGND"18;
%"CAPACITOR"
"2","(-10800,7950)","0","passive","I22";
;
$LOCATION"C41"
CDS_LOCATION"C41"
$SEC"1"
CDS_SEC"1"
VOLTAGE"25V"
VALUE"0.1UF"
PACKAGE"0402"
CDS_LIB"passive"
CDS_LMAN_SYM_OUTLINE"-50,0,50,-50"
CLS_PN"G105-0B104-EK"
TOLERANCE"10%";
"2"
$PN"2"18;
"1"
$PN"1"20;
%"GND_SG"
"1","(-8050,4700)","0","cls","I23";
;
HDL_POWER"SG"
BODY_TYPE"PLUMBING"
CDS_LIB"cls"
CDS_LMAN_SYM_OUTLINE"0,0,100,-50";
"SGND"21;
%"SOLDER_PREFORM"
"1","(-7500,5150)","0","mech","I24";
;
$LOCATION"SP1"
CDS_LOCATION"SP1"
$SEC"1"
CDS_SEC"1"
CLS_PN"G380-10015-01"
CDS_LMAN_SYM_OUTLINE"0,0,250,-200"
CDS_LIB"mech";
"2"
$PN"2"23;
"1"
$PN"1"21;
%"RESISTOR"
"2","(-5400,5450)","0","passive","I25";
;
$LOCATION"R32"
CDS_LOCATION"R32"
$SEC"1"
CDS_SEC"1"
PACKAGE"0402"
VALUE"3.24KOHM"
TOLERANCE"1%"
CDS_LMAN_SYM_OUTLINE"-50,50,50,-100"
CDS_LIB"passive"
CLS_PN"G155-03241-01";
"1"
$PN"1"24;
"2"
$PN"2"23;
%"RESISTOR"
"1","(-7100,7300)","0","passive","I26";
;
$LOCATION"R31"
CDS_LOCATION"R31"
$SEC"1"
CDS_SEC"1"
VALUE"0OHM"
PACKAGE"0402"
TOLERANCE"-"
CLS_PN"G155-100R0-J0"
CDS_LMAN_SYM_OUTLINE"-50,50,100,-50"
CDS_LIB"passive";
"1"
$PN"1"9;
"2"
$PN"2"10;
%"CAPACITOR"
"1","(-6200,7300)","0","passive","I27";
;
$LOCATION"C44"
CDS_LOCATION"C44"
$SEC"1"
CDS_SEC"1"
PACKAGE"0402"
VOLTAGE"25V"
VALUE"0.1UF"
CDS_LMAN_SYM_OUTLINE"0,50,50,-50"
CDS_LIB"passive"
CLS_PN"G105-0B104-EK"
TOLERANCE"10%";
"2"
$PN"2"22;
"1"
$PN"1"10;
%"RESISTOR"
"1","(-4800,5400)","1","passive","I28";
;
$LOCATION"R50"
CDS_LOCATION"R50"
$SEC"1"
CDS_SEC"1"
VALUE"0OHM"
NO_ASSY"TRUE"
PACKAGE"0603"
TOLERANCE"-"
CDS_LIB"passive"
CDS_LMAN_SYM_OUTLINE"-50,50,100,-50"
CLS_PN"G156-100R0-J0";
"1"
$PN"1"23;
"2"
$PN"2"24;
%"CAPACITOR"
"2","(-4000,6100)","0","passive","I29";
;
$LOCATION"C11"
CDS_LOCATION"C11"
$SEC"1"
CDS_SEC"1"
PACKAGE"0201"
VALUE"100PF"
VOLTAGE"50V"
CLS_PN"G104-0B101-FK"
CDS_LIB"passive"
CDS_LMAN_SYM_OUTLINE"-50,0,50,-50"
TOLERANCE"10%";
"2"
$PN"2"24;
"1"
$PN"1"25;
%"GND_SG"
"1","(-13750,7600)","0","cls","I3";
;
HDL_POWER"SG"
BODY_TYPE"PLUMBING"
CDS_LMAN_SYM_OUTLINE"0,0,100,-50"
CDS_LIB"cls";
"SGND"3;
%"RESISTOR"
"2","(-3350,6150)","0","passive","I30";
;
$LOCATION"R34"
CDS_LOCATION"R34"
$SEC"1"
CDS_SEC"1"
PACKAGE"0402"
VALUE"24KOHM"
TOLERANCE"1%"
CDS_LMAN_SYM_OUTLINE"-50,50,50,-100"
CDS_LIB"passive"
CLS_PN"G155-02402-01";
"1"
$PN"1"25;
"2"
$PN"2"24;
%"RESISTOR"
"2","(-3350,6700)","0","passive","I31";
;
$LOCATION"R6"
CDS_LOCATION"R6"
$SEC"1"
CDS_SEC"1"
VALUE"20OHM"
PACKAGE"0402"
TOLERANCE"1%"
CLS_PN"G155-120R0-01"
CDS_LIB"passive"
CDS_LMAN_SYM_OUTLINE"-50,50,50,-100";
"1"
$PN"1"26;
"2"
$PN"2"25;
%"CAPACITOR"
"2","(-2700,6750)","0","passive","I32";
;
$LOCATION"C12"
CDS_LOCATION"C12"
$SEC"1"
CDS_SEC"1"
VALUE"0.1UF"
PACKAGE"0402"
VOLTAGE"10V"
TOLERANCE"10%"
CDS_LMAN_SYM_OUTLINE"-50,0,50,-50"
CDS_LIB"passive"
CLS_PN"G105-0B104-CK";
"2"
$PN"2"27;
"1"
$PN"1"26;
%"CAPACITOR"
"2","(-2150,6750)","0","passive","I33";
;
$LOCATION"C13"
CDS_LOCATION"C13"
$SEC"1"
CDS_SEC"1"
PACKAGE"0805"
VALUE"22UF"
VOLTAGE"10V"
CLS_PN"G107-0F226-CM"
CDS_LIB"passive"
CDS_LMAN_SYM_OUTLINE"-50,0,50,-50"
TOLERANCE"20%";
"2"
$PN"2"27;
"1"
$PN"1"26;
%"GND_SG"
"1","(-1200,6200)","0","cls","I34";
;
HDL_POWER"SG"
BODY_TYPE"PLUMBING"
CDS_LMAN_SYM_OUTLINE"0,0,100,-50"
CDS_LIB"cls";
"SGND"27;
%"CAPACITOR"
"2","(-1650,6750)","0","passive","I35";
;
$LOCATION"C14"
CDS_LOCATION"C14"
$SEC"1"
CDS_SEC"1"
VALUE"22UF"
PACKAGE"0805"
VOLTAGE"10V"
CDS_LMAN_SYM_OUTLINE"-50,0,50,-50"
CDS_LIB"passive"
CLS_PN"G107-0F226-CM"
TOLERANCE"20%";
"2"
$PN"2"27;
"1"
$PN"1"26;
%"INDUCTOR_2"
"1","(-4850,7100)","0","passive","I36";
;
$LOCATION"L1"
CDS_LOCATION"L1"
$SEC"1"
CDS_SEC"1"
VALUE"4.7UH"
CDS_LIB"passive"
CDS_LMAN_SYM_OUTLINE"-100,50,150,-50"
CLS_PN"G190-10424-01"
TOLERANCE"20%";
"1"
$PN"1"22;
"2"
$PN"2"26;
%"CAPACITOR"
"1","(-4900,7450)","0","passive","I37";
;
$LOCATION"C45"
CDS_LOCATION"C45"
$SEC"1"
CDS_SEC"1"
PACKAGE"0402"
VALUE"1000PF"
VOLTAGE"50V"
NO_ASSY"TRUE"
TOLERANCE"5%"
CLS_PN"G105-0A102-FJ"
CDS_LIB"passive"
CDS_LMAN_SYM_OUTLINE"0,50,50,-50";
"2"
$PN"2"11;
"1"
$PN"1"22;
%"RESISTOR"
"1","(-3950,7450)","0","passive","I38";
;
$LOCATION"R33"
CDS_LOCATION"R33"
$SEC"1"
CDS_SEC"1"
PACKAGE"0805"
VALUE"2.2OHM"
NO_ASSY"TRUE"
TOLERANCE"1%"
CDS_LMAN_SYM_OUTLINE"-50,50,100,-50"
CDS_LIB"passive"
CLS_PN"G157-12R20-01";
"1"
$PN"1"11;
"2"
$PN"2"2;
%"GND_SG"
"1","(-3450,7300)","0","cls","I39";
;
HDL_POWER"SG"
BODY_TYPE"PLUMBING"
CDS_LMAN_SYM_OUTLINE"0,0,100,-50"
CDS_LIB"cls";
"SGND"2;
%"CAPACITOR"
"2","(-13700,8000)","0","passive","I4";
;
$LOCATION"C74"
CDS_LOCATION"C74"
$SEC"1"
CDS_SEC"1"
PACKAGE"0402"
VALUE"0.1UF"
VOLTAGE"25V"
CDS_LMAN_SYM_OUTLINE"-50,0,50,-50"
CDS_LIB"passive"
CLS_PN"G105-0B104-EK"
TOLERANCE"10%";
"2"
$PN"2"3;
"1"
$PN"1"8;
%"CAPACITOR"
"2","(-1150,6750)","0","passive","I40";
;
$LOCATION"C15"
CDS_LOCATION"C15"
$SEC"1"
CDS_SEC"1"
PACKAGE"0805"
VALUE"22UF"
VOLTAGE"10V"
CDS_LIB"passive"
CDS_LMAN_SYM_OUTLINE"-50,0,50,-50"
CLS_PN"G107-0F226-CM"
TOLERANCE"20%";
"2"
$PN"2"27;
"1"
$PN"1"26;
%"VCC"
"1","(-1050,7350)","0","cls","I41";
;
HDL_POWER"XP5R0V"
VOLTAGE"5.0"
BODY_TYPE"PLUMBING"
CDS_LIB"cls"
CDS_LMAN_SYM_OUTLINE"-250,250,250,-250";
"$PIN0"26;
%"TPS54824RNVR_VQFN18"
"1","(-9450,7400)","0","stdlogic","I42";
;
$LOCATION"U5"
CDS_LOCATION"U5"
$SEC"1"
CDS_SEC"1"
VALUE"TPS54424RNVT"
CLS_PN"G220-10657-01"
CDS_LIB"stdlogic"
CDS_LMAN_SYM_OUTLINE"0,0,1000,-1750";
"PGOOD"
$PN"18"14;
"EN"
$PN"17"16;
"SS/TRK"
$PN"16"12;
"COMP"
$PN"15"19;
"FB"
$PN"14"24;
"RT/CLK"
$PN"13"13;
"AGND"
$PN"12"17;
"VIN_2"
$PN"11"20;
"PGND_6"
$PN"10"21;
"PGND_5"
$PN"9"21;
"PGND_4"
$PN"8"21;
"SW_2"
$PN"7"22;
"SW_1"
$PN"6"22;
"PGND_3"
$PN"5"21;
"PGND_2"
$PN"4"21;
"PGND_1"
$PN"3"21;
"VIN_1"
$PN"2"20;
"BOOT"
$PN"1"9;
%"RESISTOR"
"1","(-13400,7000)","0","passive","I44";
;
$LOCATION"R142"
CDS_LOCATION"R142"
$SEC"1"
CDS_SEC"1"
VALUE"100OHM"
PACKAGE"0402"
TOLERANCE"1%"
CDS_LIB"passive"
CDS_LMAN_SYM_OUTLINE"-50,50,100,-50"
CLS_PN"G155-11000-01";
"1"
$PN"1"1;
"2"
$PN"2"16;
%"RESISTOR"
"1","(-11550,4900)","0","passive","I45";
;
$LOCATION"R294"
CDS_LOCATION"R294"
$SEC"1"
CDS_SEC"1"
VALUE"33OHM"
PACKAGE"0402"
NO_ASSY"TRUE"
TOLERANCE"1%"
CLS_PN"G155-133R0-01"
SIGNAL_MODEL"DEFAULT_RESISTOR_33OHM_2_1"
CDS_LMAN_SYM_OUTLINE"-50,50,100,-50"
CDS_LIB"passive";
"1"
$PN"1"14;
"2"
$PN"2"6;
%"VCC"
"1","(-13750,8700)","0","cls","I5";
;
HDL_POWER"XP12R0V"
VOLTAGE"12V"
BODY_TYPE"PLUMBING"
CDS_LIB"cls"
CDS_LMAN_SYM_OUTLINE"-250,250,250,-250";
"$PIN0"8;
%"GND_SG"
"1","(-13200,5150)","0","cls","I6";
;
HDL_POWER"SG"
BODY_TYPE"PLUMBING"
CDS_LIB"cls"
CDS_LMAN_SYM_OUTLINE"0,0,100,-50";
"SGND"5;
%"CAPACITOR"
"1","(-13150,5450)","1","passive","I7";
;
$LOCATION"C75"
CDS_LOCATION"C75"
$SEC"1"
CDS_SEC"1"
PACKAGE"0201"
VOLTAGE"25V"
VALUE"0.01UF"
CLS_PN"G104-0B103-EK"
CDS_LMAN_SYM_OUTLINE"0,50,50,-50"
CDS_LIB"passive"
TOLERANCE"10%";
"2"
$PN"2"14;
"1"
$PN"1"5;
%"GND_SG"
"1","(-12650,6050)","0","cls","I8";
;
HDL_POWER"SG"
BODY_TYPE"PLUMBING"
CDS_LMAN_SYM_OUTLINE"0,0,100,-50"
CDS_LIB"cls";
"SGND"15;
%"RESISTOR"
"2","(-12950,6600)","0","passive","I9";
;
$LOCATION"R48"
CDS_LOCATION"R48"
$SEC"1"
CDS_SEC"1"
VALUE"5.1KOHM"
PACKAGE"0402"
NO_ASSY"TRUE"
TOLERANCE"1%"
CDS_LMAN_SYM_OUTLINE"-50,50,50,-100"
CDS_LIB"passive"
CLS_PN"A155-05101-DL";
"1"
$PN"1"16;
"2"
$PN"2"15;
END.
